# S9S_MB_2U (Grand Teton) — schematic netlist excerpt (pin names and nets, part order shuffled) for the footprints in the layout excerpt that follows; sources: Cadence DE-HDL packaged netlist, KiCad conversion of 03242023_DA0F0TMBIJ0_F0T_Motherboard_J_brd_V01_OCP.brd

PC538_P1_3  Q_CAP  22UF 16V 20% X6S  pkg C0805  page 286 : A = SW_P12V_PVCCIN_CPU1_FLT ; B = GND
C1198  Q_CAP  22UF 4V 20% X6S  pkg C0603  page 189 : A = P1V05_PCH_AUX ; B = GND
PR1380  Q_RES  49.9 1% CHIP  pkg 0402LF  page 278 : A = P12V_AUX_CPU0_DIMM_ISEN_P ; B = PVCCD_HV_CPU0_ISENSE_P

(kicad_pcb
	(version 20260206)
	(generator "pcbnew")
	(generator_version "10.0")
	(general
		(thickness 1.6)
		(legacy_teardrops no)
	)
	(paper "A4")
	(title_block
		(title "03242023_DA0F0TMBIJ0_F0T_Motherboard_J_brd_V01_OCP.brd")
		(comment 1 "Grand Teton / footprints 5587-5589 of 6105")
	)
	(layers
		(0 "F.Cu" signal "TOP")
		(4 "In1.Cu" signal "GND")
		(6 "In2.Cu" signal "IN1")
		(8 "In3.Cu" signal "GND1")
		(10 "In4.Cu" signal "IN2")
		(12 "In5.Cu" signal "GND2")
		(14 "In6.Cu" signal "IN3")
		(16 "In7.Cu" signal "GND3")
		(18 "In8.Cu" signal "VCC")
		(20 "In9.Cu" signal "VCC1")
		(22 "In10.Cu" signal "GND4")
		(24 "In11.Cu" signal "IN4")
		(26 "In12.Cu" signal "GND5")
		(28 "In13.Cu" signal "IN5")
		(30 "In14.Cu" signal "GND6")
		(32 "In15.Cu" signal "IN6")
		(34 "In16.Cu" signal "GND7")
		(2 "B.Cu" signal "BOTTOM")
		(9 "F.Adhes" user "F.Adhesive")
		(11 "B.Adhes" user "B.Adhesive")
		(13 "F.Paste" user "Package Geometry/Pastemask Top")
		(15 "B.Paste" user "Package Geometry/Pastemask Bottom")
		(5 "F.SilkS" user "Ref Des/Silkscreen Top")
		(7 "B.SilkS" user "Ref Des/Silkscreen Bottom")
		(1 "F.Mask" user "Board Geometry/Soldermask Top")
		(3 "B.Mask" user "Board Geometry/Soldermask Bottom")
		(17 "Dwgs.User" user "User.Drawings")
		(19 "Cmts.User" user "User.Comments")
		(21 "Eco1.User" user "User.Eco1")
		(23 "Eco2.User" user "User.Eco2")
		(25 "Edge.Cuts" user "Board Geometry/Outline")
		(27 "Margin" user)
		(31 "F.CrtYd" user "Package Geometry/Place Bound Top")
		(29 "B.CrtYd" user "Package Geometry/Place Bound Bottom")
		(35 "F.Fab" user "Ref Des/Assembly Top")
		(33 "B.Fab" user "Ref Des/Assembly Bottom")
	)
	(footprint ""
		(layer "B.Cu")
		(at 302.35144 -47.137828 180)
		(property "Reference" "C1198"
			(at 0 0 0)
			(layer "B.SilkS")
			(hide yes)
			(effects
				(font
					(size 1.27 1.27)
				)
				(justify mirror)
			)
		)
		(property "Value" ""
			(at 0 0 0)
			(layer "B.Fab")
			(effects
				(font
					(size 1.27 1.27)
				)
				(justify mirror)
			)
		)
		(duplicate_pad_numbers_are_jumpers no)
		(fp_line
			(start 1.2954 0.5842)
			(end 1.2954 -0.5842)
			(stroke
				(width 0.1524)
				(type default)
			)
			(layer "B.SilkS")
		)
		(fp_line
			(start 1.2954 -0.5842)
			(end -1.2954 -0.5842)
			(stroke
				(width 0.1524)
				(type default)
			)
			(layer "B.SilkS")
		)
		(fp_line
			(start 0 -0.5842)
			(end 0 0.5842)
			(stroke
				(width 0.1524)
				(type default)
			)
			(layer "B.SilkS")
		)
		(fp_line
			(start -1.2954 0.5842)
			(end 1.2954 0.5842)
			(stroke
				(width 0.1524)
				(type default)
			)
			(layer "B.SilkS")
		)
		(fp_line
			(start -1.2954 -0.5842)
			(end -1.2954 0.5842)
			(stroke
				(width 0.1524)
				(type default)
			)
			(layer "B.SilkS")
		)
		(fp_line
			(start 1.1938 0.4064)
			(end 1.1938 -0.4064)
			(stroke
				(width 0.1)
				(type default)
			)
			(layer "B.Fab")
		)
		(fp_line
			(start 1.1938 -0.4064)
			(end 0.8636 -0.4064)
			(stroke
				(width 0.1)
				(type default)
			)
			(layer "B.Fab")
		)
		(fp_line
			(start 0.8636 0.4572)
			(end 0.8636 0.4064)
			(stroke
				(width 0.1)
				(type default)
			)
			(layer "B.Fab")
		)
		(fp_line
			(start 0.8636 0.4064)
			(end 1.1938 0.4064)
			(stroke
				(width 0.1)
				(type default)
			)
			(layer "B.Fab")
		)
		(fp_line
			(start 0.8636 -0.4064)
			(end 0.8636 -0.4572)
			(stroke
				(width 0.1)
				(type default)
			)
			(layer "B.Fab")
		)
		(fp_line
			(start 0.8636 -0.4572)
			(end -0.8636 -0.4572)
			(stroke
				(width 0.1)
				(type default)
			)
			(layer "B.Fab")
		)
		(fp_line
			(start -0.8636 0.4572)
			(end 0.8636 0.4572)
			(stroke
				(width 0.1)
				(type default)
			)
			(layer "B.Fab")
		)
		(fp_line
			(start -0.8636 0.4064)
			(end -0.8636 0.4572)
			(stroke
				(width 0.1)
				(type default)
			)
			(layer "B.Fab")
		)
		(fp_line
			(start -0.8636 -0.4064)
			(end -1.1938 -0.4064)
			(stroke
				(width 0.1)
				(type default)
			)
			(layer "B.Fab")
		)
		(fp_line
			(start -0.8636 -0.4572)
			(end -0.8636 -0.4064)
			(stroke
				(width 0.1)
				(type default)
			)
			(layer "B.Fab")
		)
		(fp_line
			(start -1.1938 0.4064)
			(end -0.8636 0.4064)
			(stroke
				(width 0.1)
				(type default)
			)
			(layer "B.Fab")
		)
		(fp_line
			(start -1.1938 -0.4064)
			(end -1.1938 0.4064)
			(stroke
				(width 0.1)
				(type default)
			)
			(layer "B.Fab")
		)
		(pad "1" smd rect
			(at 0.7366 0 90)
			(size 0.7112 0.8128)
			(layers "B.Cu" "B.Mask" "B.Paste")
			(net "P1V05_PCH_AUX")
		)
		(pad "2" smd rect
			(at -0.7366 0 90)
			(size 0.7112 0.8128)
			(layers "B.Cu" "B.Mask" "B.Paste")
			(net "GND")
		)
	)
	(footprint ""
		(layer "B.Cu")
		(at 114.822224 -337.607402 -90)
		(property "Reference" "PC538_P1_3"
			(at 0 0 90)
			(layer "B.SilkS")
			(hide yes)
			(effects
				(font
					(size 1.27 1.27)
				)
				(justify mirror)
			)
		)
		(property "Value" ""
			(at 0 0 90)
			(layer "B.Fab")
			(effects
				(font
					(size 1.27 1.27)
				)
				(justify mirror)
			)
		)
		(duplicate_pad_numbers_are_jumpers no)
		(fp_line
			(start -1.524 0.762)
			(end 1.524 0.762)
			(stroke
				(width 0.1524)
				(type default)
			)
			(layer "B.SilkS")
		)
		(fp_line
			(start 1.524 0.762)
			(end 1.524 -0.762)
			(stroke
				(width 0.1524)
				(type default)
			)
			(layer "B.SilkS")
		)
		(fp_line
			(start -1.524 -0.762)
			(end -1.524 0.762)
			(stroke
				(width 0.1524)
				(type default)
			)
			(layer "B.SilkS")
		)
		(fp_line
			(start 1.524 -0.762)
			(end -1.524 -0.762)
			(stroke
				(width 0.1524)
				(type default)
			)
			(layer "B.SilkS")
		)
		(fp_line
			(start -1.1049 0.724916)
			(end -1.1049 -0.724916)
			(stroke
				(width 0.1)
				(type default)
			)
			(layer "B.Fab")
		)
		(fp_line
			(start 1.1049 0.724916)
			(end -1.1049 0.724916)
			(stroke
				(width 0.1)
				(type default)
			)
			(layer "B.Fab")
		)
		(fp_line
			(start -1.1049 -0.724916)
			(end 1.1049 -0.724916)
			(stroke
				(width 0.1)
				(type default)
			)
			(layer "B.Fab")
		)
		(fp_line
			(start 1.1049 -0.724916)
			(end 1.1049 0.724916)
			(stroke
				(width 0.1)
				(type default)
			)
			(layer "B.Fab")
		)
		(pad "1" smd rect
			(at 0.889 0 270)
			(size 1.016 1.27)
			(layers "B.Cu" "B.Mask" "B.Paste")
			(net "SW_P12V_PVCCIN_CPU1_FLT")
		)
		(pad "2" smd rect
			(at -0.889 0 270)
			(size 1.016 1.27)
			(layers "B.Cu" "B.Mask" "B.Paste")
			(net "GND")
		)
	)
	(footprint ""
		(layer "B.Cu")
		(at 426.892212 -122.57786 180)
		(property "Reference" "PR1380"
			(at 0 0 0)
			(layer "B.SilkS")
			(hide yes)
			(effects
				(font
					(size 1.27 1.27)
				)
				(justify mirror)
			)
		)
		(property "Value" ""
			(at 0 0 0)
			(layer "B.Fab")
			(effects
				(font
					(size 1.27 1.27)
				)
				(justify mirror)
			)
		)
		(duplicate_pad_numbers_are_jumpers no)
		(fp_line
			(start 0.7874 0.4064)
			(end 0.7874 -0.4064)
			(stroke
				(width 0.1524)
				(type default)
			)
			(layer "B.SilkS")
		)
		(fp_line
			(start 0.7874 -0.4064)
			(end -0.7874 -0.4064)
			(stroke
				(width 0.1524)
				(type default)
			)
			(layer "B.SilkS")
		)
		(fp_line
			(start -0.7874 0.4064)
			(end 0.7874 0.4064)
			(stroke
				(width 0.1524)
				(type default)
			)
			(layer "B.SilkS")
		)
		(fp_line
			(start -0.7874 -0.4064)
			(end -0.7874 0.4064)
			(stroke
				(width 0.1524)
				(type default)
			)
			(layer "B.SilkS")
		)
		(fp_line
			(start 0.67945 0.3048)
			(end 0.67945 -0.305054)
			(stroke
				(width 0.1)
				(type default)
			)
			(layer "B.Fab")
		)
		(fp_line
			(start 0.67945 -0.305054)
			(end 0.12065 -0.305054)
			(stroke
				(width 0.1)
				(type default)
			)
			(layer "B.Fab")
		)
		(fp_line
			(start 0.12065 0.3048)
			(end 0.67945 0.3048)
			(stroke
				(width 0.1)
				(type default)
			)
			(layer "B.Fab")
		)
		(fp_line
			(start 0.12065 0.2794)
			(end 0.12065 0.3048)
			(stroke
				(width 0.1)
				(type default)
			)
			(layer "B.Fab")
		)
		(fp_line
			(start 0.12065 -0.2794)
			(end -0.12065 -0.2794)
			(stroke
				(width 0.1)
				(type default)
			)
			(layer "B.Fab")
		)
		(fp_line
			(start 0.12065 -0.305054)
			(end 0.12065 -0.2794)
			(stroke
				(width 0.1)
				(type default)
			)
			(layer "B.Fab")
		)
		(fp_line
			(start -0.120396 0.3048)
			(end -0.120396 0.2794)
			(stroke
				(width 0.1)
				(type default)
			)
			(layer "B.Fab")
		)
		(fp_line
			(start -0.120396 0.2794)
			(end 0.12065 0.2794)
			(stroke
				(width 0.1)
				(type default)
			)
			(layer "B.Fab")
		)
		(fp_line
			(start -0.12065 -0.2794)
			(end -0.12065 -0.3048)
			(stroke
				(width 0.1)
				(type default)
			)
			(layer "B.Fab")
		)
		(fp_line
			(start -0.12065 -0.3048)
			(end -0.67945 -0.3048)
			(stroke
				(width 0.1)
				(type default)
			)
			(layer "B.Fab")
		)
		(fp_line
			(start -0.67945 0.3048)
			(end -0.120396 0.3048)
			(stroke
				(width 0.1)
				(type default)
			)
			(layer "B.Fab")
		)
		(fp_line
			(start -0.67945 -0.3048)
			(end -0.67945 0.3048)
			(stroke
				(width 0.1)
				(type default)
			)
			(layer "B.Fab")
		)
		(pad "1" smd circle
			(at 0.40005 0)
			(size 0 0)
			(layers "B.Cu" "B.Mask" "B.Paste")
			(net "P12V_AUX_CPU0_DIMM_ISEN_P")
		)
		(pad "2" smd circle
			(at -0.40005 0)
			(size 0 0)
			(layers "B.Cu" "B.Mask" "B.Paste")
			(net "PVCCD_HV_CPU0_ISENSE_P")
		)
	)
)
